# BASEBOARD_FAB2 (Tioga Pass) — schematic netlist excerpt (pin names and nets, part order shuffled) for the footprints in the layout excerpt that follows; sources: Cadence DE-HDL packaged netlist, KiCad conversion of Wiwynn_Tioga_Pass_MB.brd

C3N9  CAP  0.22UF 16V 10% X7R  pkg 0402  page 129 : A = DMI_CPU0_PCH_RX_DP<2> ; B = DMI_CPU0_PCH_RX_C_DP<2>
R4P12  RES  100.0 1% CHIP  pkg 0402  page 112 : A = PVCCIO_CPU0 ; B = XDP_CPU_MBP0_N
R4E14  RES  100.0 1% CHIP  pkg 0402  page 204 : A = VSENSE_PVCCIN_CPU0_P ; B = PVCCIN_CPU0

(kicad_pcb
	(version 20260206)
	(generator "pcbnew")
	(generator_version "10.0")
	(general
		(thickness 1.6)
		(legacy_teardrops no)
	)
	(paper "A4")
	(title_block
		(title "Wiwynn_Tioga_Pass_MB.brd")
		(comment 1 "Tioga Pass / footprints 2558-2560 of 4770")
	)
	(layers
		(0 "F.Cu" signal "TOP")
		(4 "In1.Cu" signal "L2GND")
		(6 "In2.Cu" signal "L3")
		(8 "In3.Cu" signal "L4GND")
		(10 "In4.Cu" signal "L5")
		(12 "In5.Cu" signal "L6GND")
		(14 "In6.Cu" signal "L7VCC")
		(16 "In7.Cu" signal "L8VCC")
		(18 "In8.Cu" signal "L9GND")
		(20 "In9.Cu" signal "L10")
		(22 "In10.Cu" signal "L11GND")
		(24 "In11.Cu" signal "L12")
		(26 "In12.Cu" signal "L13GND")
		(2 "B.Cu" signal "BOTTOM")
		(9 "F.Adhes" user "F.Adhesive")
		(11 "B.Adhes" user "B.Adhesive")
		(13 "F.Paste" user "Package Geometry/Pastemask Top")
		(15 "B.Paste" user "Package Geometry/Pastemask Bottom")
		(5 "F.SilkS" user "Ref Des/Silkscreen Top")
		(7 "B.SilkS" user "Ref Des/Silkscreen Bottom")
		(1 "F.Mask" user "Board Geometry/Soldermask Top")
		(3 "B.Mask" user "Board Geometry/Soldermask Bottom")
		(17 "Dwgs.User" user "User.Drawings")
		(19 "Cmts.User" user "User.Comments")
		(21 "Eco1.User" user "User.Eco1")
		(23 "Eco2.User" user "User.Eco2")
		(25 "Edge.Cuts" user "Board Geometry/Outline")
		(27 "Margin" user)
		(31 "F.CrtYd" user "Package Geometry/Place Bound Top")
		(29 "B.CrtYd" user "Package Geometry/Place Bound Bottom")
		(35 "F.Fab" user "Ref Des/Assembly Top")
		(33 "B.Fab" user "Ref Des/Assembly Bottom")
	)
	(footprint ""
		(layer "B.Cu")
		(at 228.4603 -64.6557 180)
		(property "Reference" "R4E14"
			(at 0 0 0)
			(layer "B.SilkS")
			(hide yes)
			(effects
				(font
					(size 1.27 1.27)
				)
				(justify mirror)
			)
		)
		(property "Value" ""
			(at 0 0 0)
			(layer "B.Fab")
			(effects
				(font
					(size 1.27 1.27)
				)
				(justify mirror)
			)
		)
		(duplicate_pad_numbers_are_jumpers no)
		(fp_poly
			(pts
				(xy 0.2794 -0.1016) (xy -0.2794 -0.1016) (xy -0.2794 0.9906) (xy 0.2794 0.9906)
			)
			(stroke
				(width 0)
				(type default)
			)
			(fill no)
			(layer "B.CrtYd")
		)
		(fp_line
			(start 0.2794 0.9906)
			(end -0.2794 0.9906)
			(stroke
				(width 0.1)
				(type default)
			)
			(layer "B.Fab")
		)
		(fp_line
			(start 0.2794 -0.1016)
			(end 0.2794 0.9906)
			(stroke
				(width 0.1)
				(type default)
			)
			(layer "B.Fab")
		)
		(fp_line
			(start -0.2794 0.9906)
			(end -0.2794 -0.1016)
			(stroke
				(width 0.1)
				(type default)
			)
			(layer "B.Fab")
		)
		(fp_line
			(start -0.2794 -0.1016)
			(end 0.2794 -0.1016)
			(stroke
				(width 0.1)
				(type default)
			)
			(layer "B.Fab")
		)
		(pad "1" smd rect
			(at 0 0)
			(size 0.508 0.508)
			(layers "B.Cu" "B.Mask" "B.Paste")
			(net "VSENSE_PVCCIN_CPU0_P")
		)
		(pad "2" smd rect
			(at 0 0.889)
			(size 0.508 0.508)
			(layers "B.Cu" "B.Mask" "B.Paste")
			(net "PVCCIN_CPU0")
		)
		(zone
			(layer "B.Cu")
			(hatch none 0.5)
			(connect_pads
				(clearance 0)
			)
			(min_thickness 0.25)
			(keepout
				(tracks not_allowed)
				(vias allowed)
				(pads allowed)
				(copperpour not_allowed)
				(footprints allowed)
			)
			(placement
				(enabled no)
				(sheetname "")
			)
			(fill
				(thermal_gap 0.5)
				(thermal_bridge_width 0.5)
				(island_removal_mode 0)
			)
			(polygon
				(pts
					(xy 228.2063 -65.2907) (xy 228.7143 -65.2907) (xy 228.7143 -64.9097) (xy 228.2063 -64.9097)
				)
			)
		)
		(zone
			(layer "B.Cu")
			(hatch none 0.5)
			(connect_pads
				(clearance 0)
			)
			(min_thickness 0.25)
			(keepout
				(tracks allowed)
				(vias not_allowed)
				(pads allowed)
				(copperpour not_allowed)
				(footprints allowed)
			)
			(placement
				(enabled no)
				(sheetname "")
			)
			(fill
				(thermal_gap 0.5)
				(thermal_bridge_width 0.5)
				(island_removal_mode 0)
			)
			(polygon
				(pts
					(xy 228.2063 -64.9097) (xy 228.7143 -64.9097) (xy 228.7143 -65.2907) (xy 228.2063 -65.2907)
				)
			)
		)
	)
	(footprint ""
		(layer "B.Cu")
		(at 365.506 -110.998 -90)
		(property "Reference" "C3N9"
			(at 0 0 90)
			(layer "B.SilkS")
			(hide yes)
			(effects
				(font
					(size 1.27 1.27)
				)
				(justify mirror)
			)
		)
		(property "Value" ""
			(at 0 0 90)
			(layer "B.Fab")
			(effects
				(font
					(size 1.27 1.27)
				)
				(justify mirror)
			)
		)
		(duplicate_pad_numbers_are_jumpers no)
		(fp_poly
			(pts
				(xy -0.3048 -0.1016) (xy -0.3048 0.9906) (xy 0.3048 0.9906) (xy 0.3048 -0.1016)
			)
			(stroke
				(width 0)
				(type default)
			)
			(fill no)
			(layer "B.CrtYd")
		)
		(fp_line
			(start -0.3048 0.9906)
			(end -0.3048 -0.1016)
			(stroke
				(width 0.1)
				(type default)
			)
			(layer "B.Fab")
		)
		(fp_line
			(start 0.3048 0.9906)
			(end -0.3048 0.9906)
			(stroke
				(width 0.1)
				(type default)
			)
			(layer "B.Fab")
		)
		(fp_line
			(start -0.3048 -0.1016)
			(end 0.3048 -0.1016)
			(stroke
				(width 0.1)
				(type default)
			)
			(layer "B.Fab")
		)
		(fp_line
			(start 0.3048 -0.1016)
			(end 0.3048 0.9906)
			(stroke
				(width 0.1)
				(type default)
			)
			(layer "B.Fab")
		)
		(pad "1" smd rect
			(at 0 0 90)
			(size 0.508 0.508)
			(layers "B.Cu" "B.Mask" "B.Paste")
			(net "DMI_CPU0_PCH_RX_DP<2>")
		)
		(pad "2" smd rect
			(at 0 0.889 90)
			(size 0.508 0.508)
			(layers "B.Cu" "B.Mask" "B.Paste")
			(net "DMI_CPU0_PCH_RX_C_DP<2>")
		)
		(zone
			(layer "B.Cu")
			(hatch none 0.5)
			(connect_pads
				(clearance 0)
			)
			(min_thickness 0.25)
			(keepout
				(tracks not_allowed)
				(vias allowed)
				(pads allowed)
				(copperpour not_allowed)
				(footprints allowed)
			)
			(placement
				(enabled no)
				(sheetname "")
			)
			(fill
				(thermal_gap 0.5)
				(thermal_bridge_width 0.5)
				(island_removal_mode 0)
			)
			(polygon
				(pts
					(xy 364.871 -110.744) (xy 364.871 -111.252) (xy 365.252 -111.252) (xy 365.252 -110.744)
				)
			)
		)
		(zone
			(layer "B.Cu")
			(hatch none 0.5)
			(connect_pads
				(clearance 0)
			)
			(min_thickness 0.25)
			(keepout
				(tracks allowed)
				(vias not_allowed)
				(pads allowed)
				(copperpour not_allowed)
				(footprints allowed)
			)
			(placement
				(enabled no)
				(sheetname "")
			)
			(fill
				(thermal_gap 0.5)
				(thermal_bridge_width 0.5)
				(island_removal_mode 0)
			)
			(polygon
				(pts
					(xy 365.252 -110.744) (xy 365.252 -111.252) (xy 364.871 -111.252) (xy 364.871 -110.744)
				)
			)
		)
	)
	(footprint ""
		(layer "B.Cu")
		(at 330.08316 -66.25336 90)
		(property "Reference" "R4P12"
			(at 0 0 90)
			(layer "B.SilkS")
			(hide yes)
			(effects
				(font
					(size 1.27 1.27)
				)
				(justify mirror)
			)
		)
		(property "Value" ""
			(at 0 0 90)
			(layer "B.Fab")
			(effects
				(font
					(size 1.27 1.27)
				)
				(justify mirror)
			)
		)
		(duplicate_pad_numbers_are_jumpers no)
		(fp_poly
			(pts
				(xy 0.2794 -0.1016) (xy -0.2794 -0.1016) (xy -0.2794 0.9906) (xy 0.2794 0.9906)
			)
			(stroke
				(width 0)
				(type default)
			)
			(fill no)
			(layer "B.CrtYd")
		)
		(fp_line
			(start 0.2794 -0.1016)
			(end 0.2794 0.9906)
			(stroke
				(width 0.1)
				(type default)
			)
			(layer "B.Fab")
		)
		(fp_line
			(start -0.2794 -0.1016)
			(end 0.2794 -0.1016)
			(stroke
				(width 0.1)
				(type default)
			)
			(layer "B.Fab")
		)
		(fp_line
			(start 0.2794 0.9906)
			(end -0.2794 0.9906)
			(stroke
				(width 0.1)
				(type default)
			)
			(layer "B.Fab")
		)
		(fp_line
			(start -0.2794 0.9906)
			(end -0.2794 -0.1016)
			(stroke
				(width 0.1)
				(type default)
			)
			(layer "B.Fab")
		)
		(pad "1" smd rect
			(at 0 0 270)
			(size 0.508 0.508)
			(layers "B.Cu" "B.Mask" "B.Paste")
			(net "PVCCIO_CPU0")
		)
		(pad "2" smd rect
			(at 0 0.889 270)
			(size 0.508 0.508)
			(layers "B.Cu" "B.Mask" "B.Paste")
			(net "XDP_CPU_MBP0_N")
		)
		(zone
			(layer "B.Cu")
			(hatch none 0.5)
			(connect_pads
				(clearance 0)
			)
			(min_thickness 0.25)
			(keepout
				(tracks allowed)
				(vias not_allowed)
				(pads allowed)
				(copperpour not_allowed)
				(footprints allowed)
			)
			(placement
				(enabled no)
				(sheetname "")
			)
			(fill
				(thermal_gap 0.5)
				(thermal_bridge_width 0.5)
				(island_removal_mode 0)
			)
			(polygon
				(pts
					(xy 330.33716 -66.50736) (xy 330.33716 -65.99936) (xy 330.71816 -65.99936) (xy 330.71816 -66.50736)
				)
			)
		)
		(zone
			(layer "B.Cu")
			(hatch none 0.5)
			(connect_pads
				(clearance 0)
			)
			(min_thickness 0.25)
			(keepout
				(tracks not_allowed)
				(vias allowed)
				(pads allowed)
				(copperpour not_allowed)
				(footprints allowed)
			)
			(placement
				(enabled no)
				(sheetname "")
			)
			(fill
				(thermal_gap 0.5)
				(thermal_bridge_width 0.5)
				(island_removal_mode 0)
			)
			(polygon
				(pts
					(xy 330.71816 -66.50736) (xy 330.71816 -65.99936) (xy 330.33716 -65.99936) (xy 330.33716 -66.50736)
				)
			)
		)
	)
)
